# S9S_MB_2U (Grand Teton) — schematic netlist excerpt (pin names and nets, part order shuffled) for the footprints in the layout excerpt that follows; sources: Cadence DE-HDL packaged netlist, KiCad conversion of 03242023_DA0F0TMBIJ0_F0T_Motherboard_J_brd_V01_OCP.brd

R3666  Q_RES  0 5% CHIP  pkg 0402LF  page 152 : A = USB_HUB_TEST ; B = GND
R4693  Q_RES  0 5% EMPTY  pkg 0402LF  page 306 : A = HSC_CSOUT ; B = HSC_D_OC

(kicad_pcb
	(version 20260206)
	(generator "pcbnew")
	(generator_version "10.0")
	(general
		(thickness 1.6)
		(legacy_teardrops no)
	)
	(paper "A4")
	(title_block
		(title "03242023_DA0F0TMBIJ0_F0T_Motherboard_J_brd_V01_OCP.brd")
		(comment 1 "Grand Teton / footprints 4062-4063 of 6105")
	)
	(layers
		(0 "F.Cu" signal "TOP")
		(4 "In1.Cu" signal "GND")
		(6 "In2.Cu" signal "IN1")
		(8 "In3.Cu" signal "GND1")
		(10 "In4.Cu" signal "IN2")
		(12 "In5.Cu" signal "GND2")
		(14 "In6.Cu" signal "IN3")
		(16 "In7.Cu" signal "GND3")
		(18 "In8.Cu" signal "VCC")
		(20 "In9.Cu" signal "VCC1")
		(22 "In10.Cu" signal "GND4")
		(24 "In11.Cu" signal "IN4")
		(26 "In12.Cu" signal "GND5")
		(28 "In13.Cu" signal "IN5")
		(30 "In14.Cu" signal "GND6")
		(32 "In15.Cu" signal "IN6")
		(34 "In16.Cu" signal "GND7")
		(2 "B.Cu" signal "BOTTOM")
		(9 "F.Adhes" user "F.Adhesive")
		(11 "B.Adhes" user "B.Adhesive")
		(13 "F.Paste" user "Package Geometry/Pastemask Top")
		(15 "B.Paste" user "Package Geometry/Pastemask Bottom")
		(5 "F.SilkS" user "Ref Des/Silkscreen Top")
		(7 "B.SilkS" user "Ref Des/Silkscreen Bottom")
		(1 "F.Mask" user "Board Geometry/Soldermask Top")
		(3 "B.Mask" user "Board Geometry/Soldermask Bottom")
		(17 "Dwgs.User" user "User.Drawings")
		(19 "Cmts.User" user "User.Comments")
		(21 "Eco1.User" user "User.Eco1")
		(23 "Eco2.User" user "User.Eco2")
		(25 "Edge.Cuts" user "Board Geometry/Outline")
		(27 "Margin" user)
		(31 "F.CrtYd" user "Package Geometry/Place Bound Top")
		(29 "B.CrtYd" user "Package Geometry/Place Bound Bottom")
		(35 "F.Fab" user "Ref Des/Assembly Top")
		(33 "B.Fab" user "Ref Des/Assembly Bottom")
	)
	(footprint ""
		(layer "F.Cu")
		(at 14.01826 -92.687648 -90)
		(property "Reference" "R3666"
			(at 0 0 270)
			(layer "F.SilkS")
			(hide yes)
			(effects
				(font
					(size 1.27 1.27)
				)
			)
		)
		(property "Value" ""
			(at 0 0 270)
			(layer "F.Fab")
			(effects
				(font
					(size 1.27 1.27)
				)
			)
		)
		(duplicate_pad_numbers_are_jumpers no)
		(fp_line
			(start -0.7874 0.4064)
			(end -0.7874 -0.4064)
			(stroke
				(width 0.1524)
				(type default)
			)
			(layer "F.SilkS")
		)
		(fp_line
			(start 0.7874 0.4064)
			(end -0.7874 0.4064)
			(stroke
				(width 0.1524)
				(type default)
			)
			(layer "F.SilkS")
		)
		(fp_line
			(start -0.7874 -0.4064)
			(end 0.7874 -0.4064)
			(stroke
				(width 0.1524)
				(type default)
			)
			(layer "F.SilkS")
		)
		(fp_line
			(start 0.7874 -0.4064)
			(end 0.7874 0.4064)
			(stroke
				(width 0.1524)
				(type default)
			)
			(layer "F.SilkS")
		)
		(fp_line
			(start -0.67945 0.3048)
			(end -0.67945 -0.305054)
			(stroke
				(width 0.1)
				(type default)
			)
			(layer "F.Fab")
		)
		(fp_line
			(start -0.12065 0.3048)
			(end -0.67945 0.3048)
			(stroke
				(width 0.1)
				(type default)
			)
			(layer "F.Fab")
		)
		(fp_line
			(start 0.120396 0.3048)
			(end 0.120396 0.2794)
			(stroke
				(width 0.1)
				(type default)
			)
			(layer "F.Fab")
		)
		(fp_line
			(start 0.67945 0.3048)
			(end 0.120396 0.3048)
			(stroke
				(width 0.1)
				(type default)
			)
			(layer "F.Fab")
		)
		(fp_line
			(start -0.12065 0.2794)
			(end -0.12065 0.3048)
			(stroke
				(width 0.1)
				(type default)
			)
			(layer "F.Fab")
		)
		(fp_line
			(start 0.120396 0.2794)
			(end -0.12065 0.2794)
			(stroke
				(width 0.1)
				(type default)
			)
			(layer "F.Fab")
		)
		(fp_line
			(start -0.12065 -0.2794)
			(end 0.12065 -0.2794)
			(stroke
				(width 0.1)
				(type default)
			)
			(layer "F.Fab")
		)
		(fp_line
			(start 0.12065 -0.2794)
			(end 0.12065 -0.3048)
			(stroke
				(width 0.1)
				(type default)
			)
			(layer "F.Fab")
		)
		(fp_line
			(start 0.12065 -0.3048)
			(end 0.67945 -0.3048)
			(stroke
				(width 0.1)
				(type default)
			)
			(layer "F.Fab")
		)
		(fp_line
			(start 0.67945 -0.3048)
			(end 0.67945 0.3048)
			(stroke
				(width 0.1)
				(type default)
			)
			(layer "F.Fab")
		)
		(fp_line
			(start -0.67945 -0.305054)
			(end -0.12065 -0.305054)
			(stroke
				(width 0.1)
				(type default)
			)
			(layer "F.Fab")
		)
		(fp_line
			(start -0.12065 -0.305054)
			(end -0.12065 -0.2794)
			(stroke
				(width 0.1)
				(type default)
			)
			(layer "F.Fab")
		)
		(pad "1" smd circle
			(at -0.40005 0 270)
			(size 0 0)
			(layers "F.Cu" "F.Mask" "F.Paste")
			(net "USB_HUB_TEST")
		)
		(pad "2" smd circle
			(at 0.40005 0 270)
			(size 0 0)
			(layers "F.Cu" "F.Mask" "F.Paste")
			(net "GND")
		)
	)
	(footprint ""
		(layer "F.Cu")
		(at 282.73756 -424.558714 90)
		(property "Reference" "R4693"
			(at 0 0 90)
			(layer "F.SilkS")
			(hide yes)
			(effects
				(font
					(size 1.27 1.27)
				)
			)
		)
		(property "Value" ""
			(at 0 0 90)
			(layer "F.Fab")
			(effects
				(font
					(size 1.27 1.27)
				)
			)
		)
		(duplicate_pad_numbers_are_jumpers no)
		(fp_line
			(start 0.7874 -0.4064)
			(end 0.7874 0.4064)
			(stroke
				(width 0.1524)
				(type default)
			)
			(layer "F.SilkS")
		)
		(fp_line
			(start -0.7874 -0.4064)
			(end 0.7874 -0.4064)
			(stroke
				(width 0.1524)
				(type default)
			)
			(layer "F.SilkS")
		)
		(fp_line
			(start 0.7874 0.4064)
			(end -0.7874 0.4064)
			(stroke
				(width 0.1524)
				(type default)
			)
			(layer "F.SilkS")
		)
		(fp_line
			(start -0.7874 0.4064)
			(end -0.7874 -0.4064)
			(stroke
				(width 0.1524)
				(type default)
			)
			(layer "F.SilkS")
		)
		(fp_line
			(start -0.12065 -0.305054)
			(end -0.12065 -0.2794)
			(stroke
				(width 0.1)
				(type default)
			)
			(layer "F.Fab")
		)
		(fp_line
			(start -0.67945 -0.305054)
			(end -0.12065 -0.305054)
			(stroke
				(width 0.1)
				(type default)
			)
			(layer "F.Fab")
		)
		(fp_line
			(start 0.67945 -0.3048)
			(end 0.67945 0.3048)
			(stroke
				(width 0.1)
				(type default)
			)
			(layer "F.Fab")
		)
		(fp_line
			(start 0.12065 -0.3048)
			(end 0.67945 -0.3048)
			(stroke
				(width 0.1)
				(type default)
			)
			(layer "F.Fab")
		)
		(fp_line
			(start 0.12065 -0.2794)
			(end 0.12065 -0.3048)
			(stroke
				(width 0.1)
				(type default)
			)
			(layer "F.Fab")
		)
		(fp_line
			(start -0.12065 -0.2794)
			(end 0.12065 -0.2794)
			(stroke
				(width 0.1)
				(type default)
			)
			(layer "F.Fab")
		)
		(fp_line
			(start 0.120396 0.2794)
			(end -0.12065 0.2794)
			(stroke
				(width 0.1)
				(type default)
			)
			(layer "F.Fab")
		)
		(fp_line
			(start -0.12065 0.2794)
			(end -0.12065 0.3048)
			(stroke
				(width 0.1)
				(type default)
			)
			(layer "F.Fab")
		)
		(fp_line
			(start 0.67945 0.3048)
			(end 0.120396 0.3048)
			(stroke
				(width 0.1)
				(type default)
			)
			(layer "F.Fab")
		)
		(fp_line
			(start 0.120396 0.3048)
			(end 0.120396 0.2794)
			(stroke
				(width 0.1)
				(type default)
			)
			(layer "F.Fab")
		)
		(fp_line
			(start -0.12065 0.3048)
			(end -0.67945 0.3048)
			(stroke
				(width 0.1)
				(type default)
			)
			(layer "F.Fab")
		)
		(fp_line
			(start -0.67945 0.3048)
			(end -0.67945 -0.305054)
			(stroke
				(width 0.1)
				(type default)
			)
			(layer "F.Fab")
		)
		(pad "1" smd circle
			(at -0.40005 0 90)
			(size 0 0)
			(layers "F.Cu" "F.Mask" "F.Paste")
			(net "HSC_CSOUT")
		)
		(pad "2" smd circle
			(at 0.40005 0 90)
			(size 0 0)
			(layers "F.Cu" "F.Mask" "F.Paste")
			(net "HSC_D_OC")
		)
	)
)
